(kicad_pcb
	(version 20260206)
	(generator "pcbnew")
	(generator_version "10.0")
	(general
		(thickness 1.6)
		(legacy_teardrops no)
	)
	(paper "A4")
	(title_block
		(title "12092022_DA0F0TMDCD0_F0T_Management_Board_D_brd_V3_OCP.brd")
		(comment 1 "Grand Teton / footprints 610-611 of 1440")
	)
	(layers
		(0 "F.Cu" signal "TOP")
		(4 "In1.Cu" signal "GND")
		(6 "In2.Cu" signal "IN1")
		(8 "In3.Cu" signal "GND1")
		(10 "In4.Cu" signal "IN2")
		(12 "In5.Cu" signal "VCC")
		(14 "In6.Cu" signal "VCC1")
		(16 "In7.Cu" signal "IN3")
		(18 "In8.Cu" signal "GND2")
		(20 "In9.Cu" signal "IN4")
		(22 "In10.Cu" signal "GND3")
		(2 "B.Cu" signal "BOTTOM")
		(9 "F.Adhes" user "F.Adhesive")
		(11 "B.Adhes" user "B.Adhesive")
		(13 "F.Paste" user "Package Geometry/Pastemask Top")
		(15 "B.Paste" user "Package Geometry/Pastemask Bottom")
		(5 "F.SilkS" user "Ref Des/Silkscreen Top")
		(7 "B.SilkS" user "Ref Des/Silkscreen Bottom")
		(1 "F.Mask" user "Board Geometry/Soldermask Top")
		(3 "B.Mask" user "Board Geometry/Soldermask Bottom")
		(17 "Dwgs.User" user "User.Drawings")
		(19 "Cmts.User" user "User.Comments")
		(21 "Eco1.User" user "User.Eco1")
		(23 "Eco2.User" user "User.Eco2")
		(25 "Edge.Cuts" user "Board Geometry/Outline")
		(27 "Margin" user)
		(31 "F.CrtYd" user "Package Geometry/Place Bound Top")
		(29 "B.CrtYd" user "Package Geometry/Place Bound Bottom")
		(35 "F.Fab" user "Ref Des/Assembly Top")
		(33 "B.Fab" user "Ref Des/Assembly Bottom")
	)
	(footprint ""
		(layer "F.Cu")
		(at 26.75001 -77.16012 90)
		(property "Reference" "J4"
			(at -3.798062 -11.674348 90)
			(unlocked yes)
			(layer "F.SilkS")
			(effects
				(font
					(size 0.7874 0.5842)
					(thickness 0.1524)
				)
				(justify left)
			)
		)
		(property "Value" ""
			(at 0 0 90)
			(layer "F.Fab")
			(effects
				(font
					(size 1.27 1.27)
				)
			)
		)
		(duplicate_pad_numbers_are_jumpers no)
		(fp_line
			(start 1.448054 -10.925048)
			(end -1.320546 -10.925048)
			(stroke
				(width 0.1524)
				(type default)
			)
			(layer "F.SilkS")
		)
		(fp_line
			(start -1.752346 -10.925048)
			(end -3.57505 -10.925048)
			(stroke
				(width 0.1524)
				(type default)
			)
			(layer "F.SilkS")
		)
		(fp_line
			(start -3.57505 -10.925048)
			(end -3.57505 -9.271)
			(stroke
				(width 0.1524)
				(type default)
			)
			(layer "F.SilkS")
		)
		(fp_line
			(start 3.57505 -9.516618)
			(end 3.57505 -9.600692)
			(stroke
				(width 0.1524)
				(type default)
			)
			(layer "F.SilkS")
		)
		(fp_line
			(start -3.57505 -7.7216)
			(end -3.57505 -5.7785)
			(stroke
				(width 0.1524)
				(type default)
			)
			(layer "F.SilkS")
		)
		(fp_line
			(start 3.57505 -5.5245)
			(end 3.57505 -7.4676)
			(stroke
				(width 0.1524)
				(type default)
			)
			(layer "F.SilkS")
		)
		(fp_line
			(start -3.57505 9.271)
			(end -3.57505 10.925048)
			(stroke
				(width 0.1524)
				(type default)
			)
			(layer "F.SilkS")
		)
		(fp_line
			(start 3.57505 9.59866)
			(end 3.57505 9.525)
			(stroke
				(width 0.1524)
				(type default)
			)
			(layer "F.SilkS")
		)
		(fp_line
			(start -0.761746 10.925048)
			(end 1.448054 10.925048)
			(stroke
				(width 0.1524)
				(type default)
			)
			(layer "F.SilkS")
		)
		(fp_line
			(start -3.57505 10.925048)
			(end -2.260346 10.925048)
			(stroke
				(width 0.1524)
				(type default)
			)
			(layer "F.SilkS")
		)
		(fp_poly
			(pts
				(xy 5.662168 -8.741918) (xy 5.662168 -9.757918) (xy 4.646168 -9.249918)
			)
			(stroke
				(width 0)
				(type default)
			)
			(fill yes)
			(layer "F.SilkS")
		)
		(fp_line
			(start 3.57505 -10.925048)
			(end -3.57505 -10.925048)
			(stroke
				(width 0.1)
				(type default)
			)
			(layer "F.Fab")
		)
		(fp_line
			(start -3.57505 -10.925048)
			(end -3.57505 10.925048)
			(stroke
				(width 0.1)
				(type default)
			)
			(layer "F.Fab")
		)
		(fp_line
			(start 3.57505 10.925048)
			(end 3.57505 -10.925048)
			(stroke
				(width 0.1)
				(type default)
			)
			(layer "F.Fab")
		)
		(fp_line
			(start -3.57505 10.925048)
			(end 3.57505 10.925048)
			(stroke
				(width 0.1)
				(type default)
			)
			(layer "F.Fab")
		)
		(fp_poly
			(pts
				(xy 6.220968 -8.741918) (xy 6.220968 -9.757918) (xy 5.204968 -9.249918)
			)
			(stroke
				(width 0)
				(type default)
			)
			(fill yes)
			(layer "F.Fab")
		)
		(pad "" np_thru_hole circle
			(at -1.525016 -9.99998 90)
			(size 1.2192 1.2192)
			(drill 1.2192)
			(layers "*.Cu" "*.Mask")
			(clearance 0.381)
			(thermal_gap 0.381)
		)
		(pad "" np_thru_hole circle
			(at -1.525016 9.99998 90)
			(size 1.7018 1.7018)
			(drill 1.7018)
			(layers "*.Cu" "*.Mask")
			(clearance 0.381)
			(thermal_gap 0.381)
		)
		(pad "1" smd rect
			(at 3.750056 -9.249918)
			(size 0.2794 1.6002)
			(layers "F.Cu" "F.Mask" "F.Paste")
			(net "GND")
		)
		(pad "2" smd rect
			(at -3.799586 -8.999982)
			(size 0.2794 1.6002)
			(layers "F.Cu" "F.Mask" "F.Paste")
			(net "P3V3_AUX")
		)
		(pad "3" smd rect
			(at 3.750056 -8.750046)
			(size 0.2794 1.6002)
			(layers "F.Cu" "F.Mask" "F.Paste")
			(net "SPI_BMC_BT_WP1_N_R")
		)
		(pad "4" smd rect
			(at -3.799586 -8.50011)
			(size 0.2794 1.6002)
			(layers "F.Cu" "F.Mask" "F.Paste")
			(net "P3V3_AUX")
		)
		(pad "5" smd rect
			(at 3.750056 -8.24992)
			(size 0.2794 1.6002)
			(layers "F.Cu" "F.Mask" "F.Paste")
			(net "SPI_BMC_BT_WP0_N_R")
		)
		(pad "6" smd rect
			(at -3.799586 -7.999984)
			(size 0.2794 1.6002)
			(layers "F.Cu" "F.Mask" "F.Paste")
			(net "Net_1207")
		)
		(pad "7" smd rect
			(at 3.750056 -7.750048)
			(size 0.2794 1.6002)
			(layers "F.Cu" "F.Mask" "F.Paste")
			(net "GND")
		)
		(pad "16" smd rect
			(at -3.799586 -5.500116)
			(size 0.2794 1.6002)
			(layers "F.Cu" "F.Mask" "F.Paste")
			(net "BSM_PRSNT_N")
		)
		(pad "17" smd rect
			(at 3.750056 -5.249926)
			(size 0.2794 1.6002)
			(layers "F.Cu" "F.Mask" "F.Paste")
			(net "Net_1221")
		)
		(pad "18" smd rect
			(at -3.799586 -4.99999)
			(size 0.2794 1.6002)
			(layers "F.Cu" "F.Mask" "F.Paste")
			(net "GND")
		)
		(pad "19" smd rect
			(at 3.750056 -4.750054)
			(size 0.2794 1.6002)
			(layers "F.Cu" "F.Mask" "F.Paste")
			(net "RST_SPI_BMC_FLASH_R2_N")
		)
		(pad "20" smd rect
			(at -3.799586 -4.500118)
			(size 0.2794 1.6002)
			(layers "F.Cu" "F.Mask" "F.Paste")
			(net "Net_1220")
		)
		(pad "21" smd rect
			(at 3.750056 -4.249928)
			(size 0.2794 1.6002)
			(layers "F.Cu" "F.Mask" "F.Paste")
			(net "RST_SPI_BMC_FLASH_R1_N")
		)
		(pad "22" smd rect
			(at -3.799586 -3.999992)
			(size 0.2794 1.6002)
			(layers "F.Cu" "F.Mask" "F.Paste")
			(net "Net_1219")
		)
		(pad "23" smd rect
			(at 3.750056 -3.750056)
			(size 0.2794 1.6002)
			(layers "F.Cu" "F.Mask" "F.Paste")
			(net "GND")
		)
		(pad "24" smd rect
			(at -3.799586 -3.50012)
			(size 0.2794 1.6002)
			(layers "F.Cu" "F.Mask" "F.Paste")
			(net "GND")
		)
		(pad "25" smd rect
			(at 3.750056 -3.24993)
			(size 0.2794 1.6002)
			(layers "F.Cu" "F.Mask" "F.Paste")
			(net "SPI_BMC_IO1_FLASH_R")
		)
		(pad "26" smd rect
			(at -3.799586 -2.999994)
			(size 0.2794 1.6002)
			(layers "F.Cu" "F.Mask" "F.Paste")
			(net "SPI_BMC_HOLD1_N")
		)
		(pad "27" smd rect
			(at 3.750056 -2.750058)
			(size 0.2794 1.6002)
			(layers "F.Cu" "F.Mask" "F.Paste")
			(net "SPI_BMC_IO0_FLASH_R")
		)
		(pad "28" smd rect
			(at -3.799586 -2.500122)
			(size 0.2794 1.6002)
			(layers "F.Cu" "F.Mask" "F.Paste")
			(net "SPI_BMC_HOLD0_N")
		)
		(pad "29" smd rect
			(at 3.750056 -2.249932)
			(size 0.2794 1.6002)
			(layers "F.Cu" "F.Mask" "F.Paste")
			(net "GND")
		)
		(pad "30" smd rect
			(at -3.799586 -1.999996)
			(size 0.2794 1.6002)
			(layers "F.Cu" "F.Mask" "F.Paste")
			(net "GND")
		)
		(pad "31" smd rect
			(at 3.750056 -1.75006)
			(size 0.2794 1.6002)
			(layers "F.Cu" "F.Mask" "F.Paste")
			(net "SPI_BMC_CLK_FLASH_R")
		)
		(pad "32" smd rect
			(at -3.799586 -1.500124)
			(size 0.2794 1.6002)
			(layers "F.Cu" "F.Mask" "F.Paste")
			(net "Net_1218")
		)
		(pad "33" smd rect
			(at 3.750056 -1.249934)
			(size 0.2794 1.6002)
			(layers "F.Cu" "F.Mask" "F.Paste")
			(net "GND")
		)
		(pad "34" smd rect
			(at -3.799586 -0.999998)
			(size 0.2794 1.6002)
			(layers "F.Cu" "F.Mask" "F.Paste")
			(net "Net_1217")
		)
		(pad "35" smd rect
			(at 3.750056 -0.750062)
			(size 0.2794 1.6002)
			(layers "F.Cu" "F.Mask" "F.Paste")
			(net "SPI_BMC_CS1_FLASH_R_N")
		)
		(pad "36" smd rect
			(at -3.799586 -0.499872)
			(size 0.2794 1.6002)
			(layers "F.Cu" "F.Mask" "F.Paste")
			(net "GND")
		)
		(pad "37" smd rect
			(at 3.750056 -0.249936)
			(size 0.2794 1.6002)
			(layers "F.Cu" "F.Mask" "F.Paste")
			(net "SPI_BMC_CS0_FLASH_R_N")
		)
		(pad "38" smd rect
			(at -3.799586 0)
			(size 0.2794 1.6002)
			(layers "F.Cu" "F.Mask" "F.Paste")
			(net "Net_1216")
		)
		(pad "39" smd rect
			(at 3.750056 0.249936)
			(size 0.2794 1.6002)
			(layers "F.Cu" "F.Mask" "F.Paste")
			(net "GND")
		)
		(pad "40" smd rect
			(at -3.799586 0.499872)
			(size 0.2794 1.6002)
			(layers "F.Cu" "F.Mask" "F.Paste")
			(net "SMB_BMC_MM16_R1_SCL")
		)
		(pad "41" smd rect
			(at 3.750056 0.750062)
			(size 0.2794 1.6002)
			(layers "F.Cu" "F.Mask" "F.Paste")
			(net "Net_1215")
		)
		(pad "42" smd rect
			(at -3.799586 0.999998)
			(size 0.2794 1.6002)
			(layers "F.Cu" "F.Mask" "F.Paste")
			(net "SMB_BMC_MM16_R1_SDA")
		)
		(pad "43" smd rect
			(at 3.750056 1.249934)
			(size 0.2794 1.6002)
			(layers "F.Cu" "F.Mask" "F.Paste")
			(net "Net_1214")
		)
		(pad "44" smd rect
			(at -3.799586 1.500124)
			(size 0.2794 1.6002)
			(layers "F.Cu" "F.Mask" "F.Paste")
			(net "Net_1213")
		)
		(pad "45" smd rect
			(at 3.750056 1.75006)
			(size 0.2794 1.6002)
			(layers "F.Cu" "F.Mask" "F.Paste")
			(net "GND")
		)
		(pad "46" smd rect
			(at -3.799586 1.999996)
			(size 0.2794 1.6002)
			(layers "F.Cu" "F.Mask" "F.Paste")
			(net "EMMC_WP")
		)
		(pad "47" smd rect
			(at 3.750056 2.249932)
			(size 0.2794 1.6002)
			(layers "F.Cu" "F.Mask" "F.Paste")
			(net "Net_1212")
		)
		(pad "48" smd rect
			(at -3.799586 2.500122)
			(size 0.2794 1.6002)
			(layers "F.Cu" "F.Mask" "F.Paste")
			(net "Net_1211")
		)
		(pad "49" smd rect
			(at 3.750056 2.750058)
			(size 0.2794 1.6002)
			(layers "F.Cu" "F.Mask" "F.Paste")
			(net "Net_1210")
		)
		(pad "50" smd rect
			(at -3.799586 2.999994)
			(size 0.2794 1.6002)
			(layers "F.Cu" "F.Mask" "F.Paste")
			(net "Net_1209")
		)
		(pad "51" smd rect
			(at 3.750056 3.24993)
			(size 0.2794 1.6002)
			(layers "F.Cu" "F.Mask" "F.Paste")
			(net "GND")
		)
		(pad "52" smd rect
			(at -3.799586 3.50012)
			(size 0.2794 1.6002)
			(layers "F.Cu" "F.Mask" "F.Paste")
			(net "EMMC_DT7_R")
		)
		(pad "53" smd rect
			(at 3.750056 3.750056)
			(size 0.2794 1.6002)
			(layers "F.Cu" "F.Mask" "F.Paste")
			(net "Net_1208")
		)
		(pad "54" smd rect
			(at -3.799586 3.999992)
			(size 0.2794 1.6002)
			(layers "F.Cu" "F.Mask" "F.Paste")
			(net "EMMC_DT6_R")
		)
		(pad "55" smd rect
			(at 3.750056 4.249928)
			(size 0.2794 1.6002)
			(layers "F.Cu" "F.Mask" "F.Paste")
			(net "EMMC_CLK_R")
		)
		(pad "56" smd rect
			(at -3.799586 4.500118)
			(size 0.2794 1.6002)
			(layers "F.Cu" "F.Mask" "F.Paste")
			(net "EMMC_DT5_R")
		)
		(pad "57" smd rect
			(at 3.750056 4.750054)
			(size 0.2794 1.6002)
			(layers "F.Cu" "F.Mask" "F.Paste")
			(net "GND")
		)
		(pad "58" smd rect
			(at -3.799586 4.99999)
			(size 0.2794 1.6002)
			(layers "F.Cu" "F.Mask" "F.Paste")
			(net "EMMC_DT4_R")
		)
		(pad "59" smd rect
			(at 3.750056 5.249926)
			(size 0.2794 1.6002)
			(layers "F.Cu" "F.Mask" "F.Paste")
			(net "EMMC_CMD_R")
		)
		(pad "60" smd rect
			(at -3.799586 5.500116)
			(size 0.2794 1.6002)
			(layers "F.Cu" "F.Mask" "F.Paste")
			(net "Net_1206")
		)
		(pad "61" smd rect
			(at 3.750056 5.750052)
			(size 0.2794 1.6002)
			(layers "F.Cu" "F.Mask" "F.Paste")
			(net "EMMC_DT3_R")
		)
		(pad "62" smd rect
			(at -3.799586 5.999988)
			(size 0.2794 1.6002)
			(layers "F.Cu" "F.Mask" "F.Paste")
			(net "Net_1205")
		)
		(pad "63" smd rect
			(at 3.750056 6.249924)
			(size 0.2794 1.6002)
			(layers "F.Cu" "F.Mask" "F.Paste")
			(net "GND")
		)
		(pad "64" smd rect
			(at -3.799586 6.500114)
			(size 0.2794 1.6002)
			(layers "F.Cu" "F.Mask" "F.Paste")
			(net "Net_1204")
		)
		(pad "65" smd rect
			(at 3.750056 6.75005)
			(size 0.2794 1.6002)
			(layers "F.Cu" "F.Mask" "F.Paste")
			(net "EMMC_DT2_R")
		)
		(pad "66" smd rect
			(at -3.799586 6.999986)
			(size 0.2794 1.6002)
			(layers "F.Cu" "F.Mask" "F.Paste")
			(net "BMC_EMMC_RST_N")
		)
		(pad "67" smd rect
			(at 3.750056 7.249922)
			(size 0.2794 1.6002)
			(layers "F.Cu" "F.Mask" "F.Paste")
			(net "EMMC_DT1_R")
		)
		(pad "68" smd rect
			(at -3.799586 7.500112)
			(size 0.2794 1.6002)
			(layers "F.Cu" "F.Mask" "F.Paste")
			(net "Net_1203")
		)
		(pad "69" smd rect
			(at 3.750056 7.750048)
			(size 0.2794 1.6002)
			(layers "F.Cu" "F.Mask" "F.Paste")
			(net "GND")
		)
		(pad "70" smd rect
			(at -3.799586 7.999984)
			(size 0.2794 1.6002)
			(layers "F.Cu" "F.Mask" "F.Paste")
			(net "Net_1202")
		)
		(pad "71" smd rect
			(at 3.750056 8.24992)
			(size 0.2794 1.6002)
			(layers "F.Cu" "F.Mask" "F.Paste")
			(net "EMMC_DT0_R")
		)
		(pad "72" smd rect
			(at -3.799586 8.50011)
			(size 0.2794 1.6002)
			(layers "F.Cu" "F.Mask" "F.Paste")
			(net "P3V3_AUX")
		)
		(pad "73" smd rect
			(at 3.750056 8.750046)
			(size 0.2794 1.6002)
			(layers "F.Cu" "F.Mask" "F.Paste")
			(net "Net_1201")
		)
		(pad "74" smd rect
			(at -3.799586 8.999982)
			(size 0.2794 1.6002)
			(layers "F.Cu" "F.Mask" "F.Paste")
			(net "P3V3_AUX")
		)
		(pad "75" smd rect
			(at 3.750056 9.249918)
			(size 0.2794 1.6002)
			(layers "F.Cu" "F.Mask" "F.Paste")
			(net "GND")
		)
		(pad "G1" smd rect
			(at 2.975102 -10.349992)
			(size 1.2446 2.794)
			(layers "F.Cu" "F.Mask" "F.Paste")
			(net "GND")
		)
		(pad "G2" smd rect
			(at 2.975102 10.349992)
			(size 1.2446 2.794)
			(layers "F.Cu" "F.Mask" "F.Paste")
			(net "GND")
		)
		(zone
			(layers "F.Cu" "B.Cu" "In1.Cu" "In2.Cu" "In3.Cu" "In4.Cu" "In5.Cu" "In6.Cu"
				"In7.Cu" "In8.Cu" "In9.Cu" "In10.Cu"
			)
			(hatch none 0.5)
			(connect_pads
				(clearance 0)
			)
			(min_thickness 0.25)
			(keepout
				(tracks not_allowed)
				(vias allowed)
				(pads allowed)
				(copperpour not_allowed)
				(footprints allowed)
			)
			(placement
				(enabled no)
				(sheetname "")
			)
			(fill
				(thermal_gap 0.5)
				(thermal_bridge_width 0.5)
				(island_removal_mode 0)
			)
			(polygon
				(pts
					(arc
						(start 17.76603 -75.635104)
						(mid 15.73403 -75.635104)
						(end 17.76603 -75.635104)
					)
				)
			)
		)
		(zone
			(layers "F.Cu" "B.Cu" "In1.Cu" "In2.Cu" "In3.Cu" "In4.Cu" "In5.Cu" "In6.Cu"
				"In7.Cu" "In8.Cu" "In9.Cu" "In10.Cu"
			)
			(hatch none 0.5)
			(connect_pads
				(clearance 0)
			)
			(min_thickness 0.25)
			(keepout
				(tracks not_allowed)
				(vias allowed)
				(pads allowed)
				(copperpour not_allowed)
				(footprints allowed)
			)
			(placement
				(enabled no)
				(sheetname "")
			)
			(fill
				(thermal_gap 0.5)
				(thermal_bridge_width 0.5)
				(island_removal_mode 0)
			)
			(polygon
				(pts
					(arc
						(start 38.00729 -75.635104)
						(mid 35.49269 -75.635104)
						(end 38.00729 -75.635104)
					)
				)
			)
		)
	)
	(footprint ""
		(layer "F.Cu")
		(at 10.287 -96.393 90)
		(property "Reference" "R887"
			(at 0 0 90)
			(layer "F.SilkS")
			(hide yes)
			(effects
				(font
					(size 1.27 1.27)
				)
			)
		)
		(property "Value" ""
			(at 0 0 90)
			(layer "F.Fab")
			(effects
				(font
					(size 1.27 1.27)
				)
			)
		)
		(duplicate_pad_numbers_are_jumpers no)
		(fp_line
			(start 0.7874 -0.4064)
			(end 0.7874 0.4064)
			(stroke
				(width 0.1524)
				(type default)
			)
			(layer "F.SilkS")
		)
		(fp_line
			(start -0.7874 -0.4064)
			(end 0.7874 -0.4064)
			(stroke
				(width 0.1524)
				(type default)
			)
			(layer "F.SilkS")
		)
		(fp_line
			(start 0.7874 0.4064)
			(end -0.7874 0.4064)
			(stroke
				(width 0.1524)
				(type default)
			)
			(layer "F.SilkS")
		)
		(fp_line
			(start -0.7874 0.4064)
			(end -0.7874 -0.4064)
			(stroke
				(width 0.1524)
				(type default)
			)
			(layer "F.SilkS")
		)
		(fp_line
			(start -0.12065 -0.305054)
			(end -0.12065 -0.2794)
			(stroke
				(width 0.1)
				(type default)
			)
			(layer "F.Fab")
		)
		(fp_line
			(start -0.67945 -0.305054)
			(end -0.12065 -0.305054)
			(stroke
				(width 0.1)
				(type default)
			)
			(layer "F.Fab")
		)
		(fp_line
			(start 0.67945 -0.3048)
			(end 0.67945 0.3048)
			(stroke
				(width 0.1)
				(type default)
			)
			(layer "F.Fab")
		)
		(fp_line
			(start 0.12065 -0.3048)
			(end 0.67945 -0.3048)
			(stroke
				(width 0.1)
				(type default)
			)
			(layer "F.Fab")
		)
		(fp_line
			(start 0.12065 -0.2794)
			(end 0.12065 -0.3048)
			(stroke
				(width 0.1)
				(type default)
			)
			(layer "F.Fab")
		)
		(fp_line
			(start -0.12065 -0.2794)
			(end 0.12065 -0.2794)
			(stroke
				(width 0.1)
				(type default)
			)
			(layer "F.Fab")
		)
		(fp_line
			(start 0.120396 0.2794)
			(end -0.12065 0.2794)
			(stroke
				(width 0.1)
				(type default)
			)
			(layer "F.Fab")
		)
		(fp_line
			(start -0.12065 0.2794)
			(end -0.12065 0.3048)
			(stroke
				(width 0.1)
				(type default)
			)
			(layer "F.Fab")
		)
		(fp_line
			(start 0.67945 0.3048)
			(end 0.120396 0.3048)
			(stroke
				(width 0.1)
				(type default)
			)
			(layer "F.Fab")
		)
		(fp_line
			(start 0.120396 0.3048)
			(end 0.120396 0.2794)
			(stroke
				(width 0.1)
				(type default)
			)
			(layer "F.Fab")
		)
		(fp_line
			(start -0.12065 0.3048)
			(end -0.67945 0.3048)
			(stroke
				(width 0.1)
				(type default)
			)
			(layer "F.Fab")
		)
		(fp_line
			(start -0.67945 0.3048)
			(end -0.67945 -0.305054)
			(stroke
				(width 0.1)
				(type default)
			)
			(layer "F.Fab")
		)
		(pad "1" smd circle
			(at -0.40005 0 90)
			(size 0 0)
			(layers "F.Cu" "F.Mask" "F.Paste")
			(net "P3V3_AUX")
		)
		(pad "2" smd circle
			(at 0.40005 0 90)
			(size 0 0)
			(layers "F.Cu" "F.Mask" "F.Paste")
			(net "RST_BMC_HW")
		)
	)
)
